# BASEBOARD_FAB2 (Tioga Pass) — schematic netlist excerpt (pin names and nets, part order shuffled) for the footprints in the layout excerpt that follows; sources: Cadence DE-HDL packaged netlist, KiCad conversion of Wiwynn_Tioga_Pass_MB.brd

R4T6  RES  240 1.0% CHIP  pkg 0402  page 99 : A = PVCCIO_CPU0 ; B = SMB_DDR_ABC_SDA_G
R3P51  RES  6.34K 1% CHIP  pkg 0402  page 196 : A = VSENSE_P12V_ADM1085 ; B = GND
C7P19  CAP  47UF 4V 20% X6S  pkg 0805  page 76 : A = PVCCIN_CPU1 ; B = GND

(kicad_pcb
	(version 20260206)
	(generator "pcbnew")
	(generator_version "10.0")
	(general
		(thickness 1.6)
		(legacy_teardrops no)
	)
	(paper "A4")
	(title_block
		(title "Wiwynn_Tioga_Pass_MB.brd")
		(comment 1 "Tioga Pass / footprints 3153-3155 of 4770")
	)
	(layers
		(0 "F.Cu" signal "TOP")
		(4 "In1.Cu" signal "L2GND")
		(6 "In2.Cu" signal "L3")
		(8 "In3.Cu" signal "L4GND")
		(10 "In4.Cu" signal "L5")
		(12 "In5.Cu" signal "L6GND")
		(14 "In6.Cu" signal "L7VCC")
		(16 "In7.Cu" signal "L8VCC")
		(18 "In8.Cu" signal "L9GND")
		(20 "In9.Cu" signal "L10")
		(22 "In10.Cu" signal "L11GND")
		(24 "In11.Cu" signal "L12")
		(26 "In12.Cu" signal "L13GND")
		(2 "B.Cu" signal "BOTTOM")
		(9 "F.Adhes" user "F.Adhesive")
		(11 "B.Adhes" user "B.Adhesive")
		(13 "F.Paste" user "Package Geometry/Pastemask Top")
		(15 "B.Paste" user "Package Geometry/Pastemask Bottom")
		(5 "F.SilkS" user "Ref Des/Silkscreen Top")
		(7 "B.SilkS" user "Ref Des/Silkscreen Bottom")
		(1 "F.Mask" user "Board Geometry/Soldermask Top")
		(3 "B.Mask" user "Board Geometry/Soldermask Bottom")
		(17 "Dwgs.User" user "User.Drawings")
		(19 "Cmts.User" user "User.Comments")
		(21 "Eco1.User" user "User.Eco1")
		(23 "Eco2.User" user "User.Eco2")
		(25 "Edge.Cuts" user "Board Geometry/Outline")
		(27 "Margin" user)
		(31 "F.CrtYd" user "Package Geometry/Place Bound Top")
		(29 "B.CrtYd" user "Package Geometry/Place Bound Bottom")
		(35 "F.Fab" user "Ref Des/Assembly Top")
		(33 "B.Fab" user "Ref Des/Assembly Bottom")
	)
	(footprint ""
		(layer "B.Cu")
		(at 417.576 -8.1915)
		(property "Reference" "R3P51"
			(at 0 0 0)
			(layer "B.SilkS")
			(hide yes)
			(effects
				(font
					(size 1.27 1.27)
				)
				(justify mirror)
			)
		)
		(property "Value" ""
			(at 0 0 0)
			(layer "B.Fab")
			(effects
				(font
					(size 1.27 1.27)
				)
				(justify mirror)
			)
		)
		(duplicate_pad_numbers_are_jumpers no)
		(fp_rect
			(start 0.2794 -0.1016)
			(end -0.2794 0.9906)
			(stroke
				(width 0)
				(type default)
			)
			(fill no)
			(layer "B.CrtYd")
		)
		(fp_line
			(start -0.2794 -0.1016)
			(end 0.2794 -0.1016)
			(stroke
				(width 0.1)
				(type default)
			)
			(layer "B.Fab")
		)
		(fp_line
			(start -0.2794 0.9906)
			(end -0.2794 -0.1016)
			(stroke
				(width 0.1)
				(type default)
			)
			(layer "B.Fab")
		)
		(fp_line
			(start 0.2794 -0.1016)
			(end 0.2794 0.9906)
			(stroke
				(width 0.1)
				(type default)
			)
			(layer "B.Fab")
		)
		(fp_line
			(start 0.2794 0.9906)
			(end -0.2794 0.9906)
			(stroke
				(width 0.1)
				(type default)
			)
			(layer "B.Fab")
		)
		(pad "1" smd rect
			(at 0 0 180)
			(size 0.508 0.508)
			(layers "B.Cu" "B.Mask" "B.Paste")
			(net "VSENSE_P12V_ADM1085")
		)
		(pad "2" smd rect
			(at 0 0.889 180)
			(size 0.508 0.508)
			(layers "B.Cu" "B.Mask" "B.Paste")
			(net "GND")
		)
		(zone
			(layer "B.Cu")
			(hatch none 0.5)
			(connect_pads
				(clearance 0)
			)
			(min_thickness 0.25)
			(keepout
				(tracks not_allowed)
				(vias allowed)
				(pads allowed)
				(copperpour not_allowed)
				(footprints allowed)
			)
			(placement
				(enabled no)
				(sheetname "")
			)
			(fill
				(thermal_gap 0.5)
				(thermal_bridge_width 0.5)
				(island_removal_mode 0)
			)
			(polygon
				(pts
					(xy 417.83 -7.9375) (xy 417.322 -7.9375) (xy 417.322 -7.5565) (xy 417.83 -7.5565)
				)
			)
		)
		(zone
			(layer "B.Cu")
			(hatch none 0.5)
			(connect_pads
				(clearance 0)
			)
			(min_thickness 0.25)
			(keepout
				(tracks allowed)
				(vias not_allowed)
				(pads allowed)
				(copperpour not_allowed)
				(footprints allowed)
			)
			(placement
				(enabled no)
				(sheetname "")
			)
			(fill
				(thermal_gap 0.5)
				(thermal_bridge_width 0.5)
				(island_removal_mode 0)
			)
			(polygon
				(pts
					(xy 417.83 -7.9375) (xy 417.322 -7.9375) (xy 417.322 -7.5565) (xy 417.83 -7.5565)
				)
			)
		)
	)
	(footprint ""
		(layer "B.Cu")
		(at 321.1957 -31.92018 90)
		(property "Reference" "R4T6"
			(at 0 0 90)
			(layer "B.SilkS")
			(hide yes)
			(effects
				(font
					(size 1.27 1.27)
				)
				(justify mirror)
			)
		)
		(property "Value" ""
			(at 0 0 90)
			(layer "B.Fab")
			(effects
				(font
					(size 1.27 1.27)
				)
				(justify mirror)
			)
		)
		(duplicate_pad_numbers_are_jumpers no)
		(fp_poly
			(pts
				(xy 0.2794 -0.1016) (xy -0.2794 -0.1016) (xy -0.2794 0.9906) (xy 0.2794 0.9906)
			)
			(stroke
				(width 0)
				(type default)
			)
			(fill no)
			(layer "B.CrtYd")
		)
		(fp_line
			(start 0.2794 -0.1016)
			(end 0.2794 0.9906)
			(stroke
				(width 0.1)
				(type default)
			)
			(layer "B.Fab")
		)
		(fp_line
			(start -0.2794 -0.1016)
			(end 0.2794 -0.1016)
			(stroke
				(width 0.1)
				(type default)
			)
			(layer "B.Fab")
		)
		(fp_line
			(start 0.2794 0.9906)
			(end -0.2794 0.9906)
			(stroke
				(width 0.1)
				(type default)
			)
			(layer "B.Fab")
		)
		(fp_line
			(start -0.2794 0.9906)
			(end -0.2794 -0.1016)
			(stroke
				(width 0.1)
				(type default)
			)
			(layer "B.Fab")
		)
		(pad "1" smd rect
			(at 0 0 270)
			(size 0.508 0.508)
			(layers "B.Cu" "B.Mask" "B.Paste")
			(net "PVCCIO_CPU0")
		)
		(pad "2" smd rect
			(at 0 0.889 270)
			(size 0.508 0.508)
			(layers "B.Cu" "B.Mask" "B.Paste")
			(net "SMB_DDR_ABC_SDA_G")
		)
		(zone
			(layer "B.Cu")
			(hatch none 0.5)
			(connect_pads
				(clearance 0)
			)
			(min_thickness 0.25)
			(keepout
				(tracks allowed)
				(vias not_allowed)
				(pads allowed)
				(copperpour not_allowed)
				(footprints allowed)
			)
			(placement
				(enabled no)
				(sheetname "")
			)
			(fill
				(thermal_gap 0.5)
				(thermal_bridge_width 0.5)
				(island_removal_mode 0)
			)
			(polygon
				(pts
					(xy 321.4497 -32.17418) (xy 321.4497 -31.66618) (xy 321.8307 -31.66618) (xy 321.8307 -32.17418)
				)
			)
		)
		(zone
			(layer "B.Cu")
			(hatch none 0.5)
			(connect_pads
				(clearance 0)
			)
			(min_thickness 0.25)
			(keepout
				(tracks not_allowed)
				(vias allowed)
				(pads allowed)
				(copperpour not_allowed)
				(footprints allowed)
			)
			(placement
				(enabled no)
				(sheetname "")
			)
			(fill
				(thermal_gap 0.5)
				(thermal_bridge_width 0.5)
				(island_removal_mode 0)
			)
			(polygon
				(pts
					(xy 321.8307 -32.17418) (xy 321.8307 -31.66618) (xy 321.4497 -31.66618) (xy 321.4497 -32.17418)
				)
			)
		)
	)
	(footprint ""
		(layer "B.Cu")
		(at 110.261654 -68.17614 180)
		(property "Reference" "C7P19"
			(at 0 0 0)
			(layer "B.SilkS")
			(hide yes)
			(effects
				(font
					(size 1.27 1.27)
				)
				(justify mirror)
			)
		)
		(property "Value" ""
			(at 0 0 0)
			(layer "B.Fab")
			(effects
				(font
					(size 1.27 1.27)
				)
				(justify mirror)
			)
		)
		(duplicate_pad_numbers_are_jumpers no)
		(fp_poly
			(pts
				(xy 0.7239 -0.2159) (xy -0.7239 -0.2159) (xy -0.7239 1.9939) (xy 0.7239 1.9939)
			)
			(stroke
				(width 0)
				(type default)
			)
			(fill no)
			(layer "B.CrtYd")
		)
		(fp_line
			(start 0.7239 1.9939)
			(end -0.7239 1.9939)
			(stroke
				(width 0.1)
				(type default)
			)
			(layer "B.Fab")
		)
		(fp_line
			(start 0.7239 -0.2159)
			(end 0.7239 1.9939)
			(stroke
				(width 0.1)
				(type default)
			)
			(layer "B.Fab")
		)
		(fp_line
			(start -0.7239 1.9939)
			(end -0.7239 -0.2159)
			(stroke
				(width 0.1)
				(type default)
			)
			(layer "B.Fab")
		)
		(fp_line
			(start -0.7239 -0.2159)
			(end 0.7239 -0.2159)
			(stroke
				(width 0.1)
				(type default)
			)
			(layer "B.Fab")
		)
		(pad "1" smd rect
			(at 0 0)
			(size 1.27 1.016)
			(layers "B.Cu" "B.Mask" "B.Paste")
			(net "PVCCIN_CPU1")
		)
		(pad "2" smd rect
			(at 0 1.778)
			(size 1.27 1.016)
			(layers "B.Cu" "B.Mask" "B.Paste")
			(net "GND")
		)
		(zone
			(layer "B.Cu")
			(hatch none 0.5)
			(connect_pads
				(clearance 0)
			)
			(min_thickness 0.25)
			(keepout
				(tracks not_allowed)
				(vias allowed)
				(pads allowed)
				(copperpour not_allowed)
				(footprints allowed)
			)
			(placement
				(enabled no)
				(sheetname "")
			)
			(fill
				(thermal_gap 0.5)
				(thermal_bridge_width 0.5)
				(island_removal_mode 0)
			)
			(polygon
				(pts
					(xy 109.626654 -68.68414) (xy 110.896654 -68.68414) (xy 110.896654 -69.44614) (xy 109.626654 -69.44614)
				)
			)
		)
	)
)
